(kicad_pcb
	(version 20240108)
	(generator "pcbnew")
	(generator_version "8.0")
	(general
		(thickness 1.6)
		(legacy_teardrops no)
	)
	(paper "A4")
	(title_block
		(title "Jetson Orin Baseboard OCuLink Expansion")
		(date "2025-03-18")
		(rev "1.1.0")
		(company "Antmicro Ltd")
		(comment 1 "www.antmicro.com")
		(comment 9 "footprints 39-43 of 119")
	)
	(layers
		(0 "F.Cu" signal)
		(1 "In1.Cu" signal)
		(2 "In2.Cu" signal)
		(31 "B.Cu" signal)
		(32 "B.Adhes" user "B.Adhesive")
		(33 "F.Adhes" user "F.Adhesive")
		(34 "B.Paste" user)
		(35 "F.Paste" user)
		(36 "B.SilkS" user "B.Silkscreen")
		(37 "F.SilkS" user "F.Silkscreen")
		(38 "B.Mask" user)
		(39 "F.Mask" user)
		(40 "Dwgs.User" user "User.Drawings")
		(41 "Cmts.User" user "User.Comments")
		(42 "Eco1.User" user "User.Eco1")
		(43 "Eco2.User" user "User.Eco2")
		(44 "Edge.Cuts" user)
		(45 "Margin" user)
		(46 "B.CrtYd" user "B.Courtyard")
		(47 "F.CrtYd" user "F.Courtyard")
		(48 "B.Fab" user)
		(49 "F.Fab" user)
	)
	(footprint "antmicro-footprints:C_0805_2012Metric"
		(layer "F.Cu")
		(at 143.6 116.499)
		(descr "Capacitor SMD 0805")
		(tags "capacitor SMD 0805")
		(property "Reference" "C32"
			(at -1.05 -0.899 0)
			(layer "F.SilkS")
			(effects
				(font
					(size 0.7 0.7)
					(thickness 0.15)
				)
				(justify left bottom)
			)
		)
		(property "Value" "C_100u_0805"
			(at -2.055717 1.963152 0)
			(layer "F.Fab")
			(effects
				(font
					(size 0.7 0.7)
					(thickness 0.15)
				)
				(justify left bottom)
			)
		)
		(property "Footprint" "antmicro-footprints:C_0805_2012Metric"
			(at 0 0 0)
			(layer "F.Fab")
			(hide yes)
			(effects
				(font
					(size 1.27 1.27)
					(thickness 0.15)
				)
			)
		)
		(property "Datasheet" "https://www.murata.com/products/productdetail?partno=GRM21BR60J107ME15%23"
			(at 0 0 0)
			(layer "F.Fab")
			(hide yes)
			(effects
				(font
					(size 1.27 1.27)
					(thickness 0.15)
				)
			)
		)
		(property "Description" "SMD Multilayer Ceramic Capacitor, 100 µF, 6.3 V, 0805 [2012 Metric], ± 20%, X5R, GRM Series"
			(at 0 0 0)
			(layer "F.Fab")
			(hide yes)
			(effects
				(font
					(size 1.27 1.27)
					(thickness 0.15)
				)
			)
		)
		(property "MPN" "GRM21BR60J107ME15L"
			(at 0 0 0)
			(unlocked yes)
			(layer "F.Fab")
			(hide yes)
			(effects
				(font
					(size 1 1)
					(thickness 0.15)
				)
			)
		)
		(property "Manufacturer" "Murata"
			(at 0 0 0)
			(unlocked yes)
			(layer "F.Fab")
			(hide yes)
			(effects
				(font
					(size 1 1)
					(thickness 0.15)
				)
			)
		)
		(property "License" "Apache-2.0"
			(at 0 0 0)
			(unlocked yes)
			(layer "F.Fab")
			(hide yes)
			(effects
				(font
					(size 1 1)
					(thickness 0.15)
				)
			)
		)
		(property "Author" "Antmicro"
			(at 0 0 0)
			(unlocked yes)
			(layer "F.Fab")
			(hide yes)
			(effects
				(font
					(size 1 1)
					(thickness 0.15)
				)
			)
		)
		(property "Val" "100u"
			(at 0 0 0)
			(unlocked yes)
			(layer "F.Fab")
			(hide yes)
			(effects
				(font
					(size 1 1)
					(thickness 0.15)
				)
			)
		)
		(property "Voltage" ""
			(at 0 0 0)
			(unlocked yes)
			(layer "F.Fab")
			(hide yes)
			(effects
				(font
					(size 1 1)
					(thickness 0.15)
				)
			)
		)
		(property "Dielectric" ""
			(at 0 0 0)
			(unlocked yes)
			(layer "F.Fab")
			(hide yes)
			(effects
				(font
					(size 1 1)
					(thickness 0.15)
				)
			)
		)
		(property "Public" "False"
			(at 0 0 0)
			(unlocked yes)
			(layer "F.Fab")
			(hide yes)
			(effects
				(font
					(size 1 1)
					(thickness 0.15)
				)
			)
		)
		(sheetname "Root")
		(sheetfile "jetson-orin-baseboard-oculink-expansion.kicad_sch")
		(attr smd)
		(fp_line
			(start -0.3 -0.7)
			(end 0.3 -0.7)
			(stroke
				(width 0.15)
				(type solid)
			)
			(layer "F.SilkS")
		)
		(fp_line
			(start -0.3 0.7)
			(end 0.3 0.7)
			(stroke
				(width 0.15)
				(type solid)
			)
			(layer "F.SilkS")
		)
		(fp_rect
			(start 1.95 -0.9)
			(end -1.95 0.9)
			(stroke
				(width 0.05)
				(type default)
			)
			(fill none)
			(layer "F.CrtYd")
		)
		(fp_rect
			(start -0.95 -0.675)
			(end 0.95 0.675)
			(stroke
				(width 0.15)
				(type solid)
			)
			(fill none)
			(layer "F.Fab")
		)
		(fp_text user "Author: Antmicro"
			(at -1.9 5.947 0)
			(layer "F.Fab")
			(hide yes)
			(effects
				(font
					(size 0.7 0.7)
					(thickness 0.15)
				)
				(justify left bottom)
			)
		)
		(fp_text user "License: Apache-2.0"
			(at -1.9 4.947 0)
			(layer "F.Fab")
			(hide yes)
			(effects
				(font
					(size 0.7 0.7)
					(thickness 0.15)
				)
				(justify left bottom)
			)
		)
		(fp_text user "${REFERENCE}"
			(at -1.9 3.947 0)
			(layer "F.Fab")
			(hide yes)
			(effects
				(font
					(size 0.7 0.7)
					(thickness 0.15)
				)
				(justify left bottom)
			)
		)
		(pad "1" smd roundrect
			(at -1.1 0)
			(size 1.2 1.3)
			(layers "F.Cu" "F.Paste" "F.Mask")
			(roundrect_rratio 0.25)
			(net 51 "GND")
			(pintype "passive")
		)
		(pad "2" smd roundrect
			(at 1.1 0)
			(size 1.2 1.3)
			(layers "F.Cu" "F.Paste" "F.Mask")
			(roundrect_rratio 0.25)
			(net 134 "Net-(U4-OUT)")
			(pintype "passive")
		)
	)
	(footprint "antmicro-footprints:TP_SMD_0.75mm"
		(layer "F.Cu")
		(at 131.01 114.64 180)
		(property "Reference" "TP18"
			(at -1.83 1.27 180)
			(layer "F.SilkS")
			(effects
				(font
					(size 0.7 0.7)
					(thickness 0.15)
				)
				(justify right top)
			)
		)
		(property "Value" "TP_0.75mm_SMD"
			(at 0 1.2 0)
			(layer "F.Fab")
			(effects
				(font
					(size 0.7 0.7)
					(thickness 0.15)
				)
				(justify right top)
			)
		)
		(property "Footprint" "antmicro-footprints:TP_SMD_0.75mm"
			(at 0 0 0)
			(layer "F.Fab")
			(hide yes)
			(effects
				(font
					(size 1.27 1.27)
					(thickness 0.15)
				)
			)
		)
		(property "Description" "SMT test point"
			(at 0 0 0)
			(layer "F.Fab")
			(hide yes)
			(effects
				(font
					(size 1.27 1.27)
					(thickness 0.15)
				)
			)
		)
		(property "MPN" ""
			(at 0 0 180)
			(unlocked yes)
			(layer "F.Fab")
			(hide yes)
			(effects
				(font
					(size 1 1)
					(thickness 0.15)
				)
			)
		)
		(property "Manufacturer" ""
			(at 0 0 180)
			(unlocked yes)
			(layer "F.Fab")
			(hide yes)
			(effects
				(font
					(size 1 1)
					(thickness 0.15)
				)
			)
		)
		(property "Author" "Antmicro"
			(at 0 0 180)
			(unlocked yes)
			(layer "F.Fab")
			(hide yes)
			(effects
				(font
					(size 1 1)
					(thickness 0.15)
				)
			)
		)
		(property "License" "Apache-2.0"
			(at 0 0 180)
			(unlocked yes)
			(layer "F.Fab")
			(hide yes)
			(effects
				(font
					(size 1 1)
					(thickness 0.15)
				)
			)
		)
		(property "Public" "False"
			(at 0 0 180)
			(unlocked yes)
			(layer "F.Fab")
			(hide yes)
			(effects
				(font
					(size 1 1)
					(thickness 0.15)
				)
			)
		)
		(sheetname "Root")
		(sheetfile "jetson-orin-baseboard-oculink-expansion.kicad_sch")
		(attr exclude_from_pos_files exclude_from_bom)
		(fp_circle
			(center 0 0)
			(end 0.475 0)
			(stroke
				(width 0.05)
				(type default)
			)
			(fill none)
			(layer "F.CrtYd")
		)
		(fp_text user "License: Apache-2.0"
			(at -0.4 5.101 0)
			(layer "F.Fab")
			(hide yes)
			(effects
				(font
					(size 0.7 0.7)
					(thickness 0.15)
				)
				(justify right top)
			)
		)
		(fp_text user "Author: Antmicro"
			(at -0.4 3.901 0)
			(layer "F.Fab")
			(hide yes)
			(effects
				(font
					(size 0.7 0.7)
					(thickness 0.15)
				)
				(justify right top)
			)
		)
		(fp_text user "${REFERENCE}"
			(at -0.4 2.7 0)
			(layer "F.Fab")
			(hide yes)
			(effects
				(font
					(size 0.7 0.7)
					(thickness 0.15)
				)
				(justify right top)
			)
		)
		(pad "1" smd circle
			(at 0 0 180)
			(size 0.75 0.75)
			(layers "F.Cu" "F.Mask")
			(net 106 "Net-(U2-SCL)")
			(pinfunction "1")
			(pintype "passive")
		)
	)
	(footprint "antmicro-footprints:MP_Pad5.4mm_Drill2.7mm"
		(layer "F.Cu")
		(at 135.9 144.97)
		(descr "Mounting Hole 2.7mm, M2.5")
		(tags "mounting hole 2.7mm m2.5")
		(property "Reference" "MP1"
			(at -2.6 -2.27 90)
			(layer "F.SilkS")
			(effects
				(font
					(size 0.7 0.7)
					(thickness 0.15)
				)
				(justify left bottom)
			)
		)
		(property "Value" "MP_Pad5.4mm_Drill2.7mm"
			(at 0 3.6 0)
			(layer "F.Fab")
			(effects
				(font
					(size 0.7 0.7)
					(thickness 0.15)
				)
				(justify left bottom)
			)
		)
		(property "Footprint" "antmicro-footprints:MP_Pad5.4mm_Drill2.7mm"
			(at 0 0 0)
			(layer "F.Fab")
			(hide yes)
			(effects
				(font
					(size 1.27 1.27)
					(thickness 0.15)
				)
			)
		)
		(property "Description" "Mechanical part"
			(at 0 0 0)
			(layer "F.Fab")
			(hide yes)
			(effects
				(font
					(size 1.27 1.27)
					(thickness 0.15)
				)
			)
		)
		(property "Author" "Antmicro"
			(at 0 0 0)
			(unlocked yes)
			(layer "F.Fab")
			(hide yes)
			(effects
				(font
					(size 1 1)
					(thickness 0.15)
				)
			)
		)
		(property "License" "Apache-2.0"
			(at 0 0 0)
			(unlocked yes)
			(layer "F.Fab")
			(hide yes)
			(effects
				(font
					(size 1 1)
					(thickness 0.15)
				)
			)
		)
		(sheetname "Root")
		(sheetfile "jetson-orin-baseboard-oculink-expansion.kicad_sch")
		(attr exclude_from_pos_files exclude_from_bom)
		(fp_circle
			(center 0 0)
			(end 2.95 0)
			(stroke
				(width 0.05)
				(type default)
			)
			(fill none)
			(layer "F.CrtYd")
		)
		(fp_text user "License: Apache-2.0"
			(at -8.4 8.4 0)
			(layer "F.Fab")
			(hide yes)
			(effects
				(font
					(size 0.7 0.7)
					(thickness 0.15)
				)
				(justify left bottom)
			)
		)
		(fp_text user "Author: Antmicro"
			(at -8.4 7.2 0)
			(layer "F.Fab")
			(hide yes)
			(effects
				(font
					(size 0.7 0.7)
					(thickness 0.15)
				)
				(justify left bottom)
			)
		)
		(fp_text user "${REFERENCE}"
			(at -8.4 6 0)
			(layer "F.Fab")
			(hide yes)
			(effects
				(font
					(size 0.7 0.7)
					(thickness 0.15)
				)
				(justify left bottom)
			)
		)
		(pad "1" thru_hole circle
			(at 0 0)
			(size 5.4 5.4)
			(drill 2.7)
			(layers "*.Cu" "*.Mask")
			(remove_unused_layers no)
			(net 51 "GND")
			(pintype "passive")
			(solder_paste_margin_ratio -1)
		)
	)
	(footprint "antmicro-footprints:C_0402_1005Metric"
		(layer "F.Cu")
		(at 128.75 144.65 90)
		(descr "Capacitor SMD 0402")
		(tags "capacitor SMD 0402")
		(property "Reference" "C2"
			(at -0.830534 -0.62175 90)
			(layer "F.SilkS")
			(effects
				(font
					(size 0.7 0.7)
					(thickness 0.15)
				)
				(justify left bottom)
			)
		)
		(property "Value" "C_10u_0402"
			(at -1.022927 2.155213 90)
			(layer "F.Fab")
			(effects
				(font
					(size 0.7 0.7)
					(thickness 0.15)
				)
				(justify left bottom)
			)
		)
		(property "Footprint" "antmicro-footprints:C_0402_1005Metric"
			(at 0 0 90)
			(layer "F.Fab")
			(hide yes)
			(effects
				(font
					(size 1.27 1.27)
					(thickness 0.15)
				)
			)
		)
		(property "Datasheet" "https://www.yageo.com/en/Chart/Download/pdf/CC0402MRX5R5BB106"
			(at 0 0 90)
			(layer "F.Fab")
			(hide yes)
			(effects
				(font
					(size 1.27 1.27)
					(thickness 0.15)
				)
			)
		)
		(property "Description" "SMD Multilayer Ceramic Capacitor, 10 µF, 6.3 V, 0402 [1005 Metric], ± 20%, X5R, CC Series"
			(at 0 0 90)
			(layer "F.Fab")
			(hide yes)
			(effects
				(font
					(size 1.27 1.27)
					(thickness 0.15)
				)
			)
		)
		(property "MPN" "CC0402MRX5R5BB106"
			(at 0 0 90)
			(unlocked yes)
			(layer "F.Fab")
			(hide yes)
			(effects
				(font
					(size 1 1)
					(thickness 0.15)
				)
			)
		)
		(property "Manufacturer" "YAGEO"
			(at 0 0 90)
			(unlocked yes)
			(layer "F.Fab")
			(hide yes)
			(effects
				(font
					(size 1 1)
					(thickness 0.15)
				)
			)
		)
		(property "License" "Apache-2.0"
			(at 0 0 90)
			(unlocked yes)
			(layer "F.Fab")
			(hide yes)
			(effects
				(font
					(size 1 1)
					(thickness 0.15)
				)
			)
		)
		(property "Author" "Antmicro"
			(at 0 0 90)
			(unlocked yes)
			(layer "F.Fab")
			(hide yes)
			(effects
				(font
					(size 1 1)
					(thickness 0.15)
				)
			)
		)
		(property "Val" "10u"
			(at 0 0 90)
			(unlocked yes)
			(layer "F.Fab")
			(hide yes)
			(effects
				(font
					(size 1 1)
					(thickness 0.15)
				)
			)
		)
		(property "Voltage" ""
			(at 0 0 90)
			(unlocked yes)
			(layer "F.Fab")
			(hide yes)
			(effects
				(font
					(size 1 1)
					(thickness 0.15)
				)
			)
		)
		(property "Dielectric" ""
			(at 0 0 90)
			(unlocked yes)
			(layer "F.Fab")
			(hide yes)
			(effects
				(font
					(size 1 1)
					(thickness 0.15)
				)
			)
		)
		(sheetname "Root")
		(sheetfile "jetson-orin-baseboard-oculink-expansion.kicad_sch")
		(attr smd)
		(fp_rect
			(start -0.925 -0.47)
			(end 0.925 0.47)
			(stroke
				(width 0.05)
				(type default)
			)
			(fill none)
			(layer "F.CrtYd")
		)
		(fp_line
			(start 0.504 -0.25)
			(end 0.504 0.248)
			(stroke
				(width 0.15)
				(type solid)
			)
			(layer "F.Fab")
		)
		(fp_line
			(start -0.494 -0.25)
			(end 0.504 -0.25)
			(stroke
				(width 0.15)
				(type solid)
			)
			(layer "F.Fab")
		)
		(fp_line
			(start 0.504 0.248)
			(end -0.494 0.248)
			(stroke
				(width 0.15)
				(type solid)
			)
			(layer "F.Fab")
		)
		(fp_line
			(start -0.494 0.248)
			(end -0.494 -0.25)
			(stroke
				(width 0.15)
				(type solid)
			)
			(layer "F.Fab")
		)
		(fp_text user "License: Apache-2.0"
			(at -0.939 5.799 90)
			(layer "F.Fab")
			(hide yes)
			(effects
				(font
					(size 0.7 0.7)
					(thickness 0.15)
				)
				(justify left bottom)
			)
		)
		(fp_text user "${REFERENCE}"
			(at -0.939 4.599 90)
			(layer "F.Fab")
			(hide yes)
			(effects
				(font
					(size 0.7 0.7)
					(thickness 0.15)
				)
				(justify left bottom)
			)
		)
		(fp_text user "Author: Antmicro"
			(at -0.939 3.399 90)
			(layer "F.Fab")
			(hide yes)
			(effects
				(font
					(size 0.7 0.7)
					(thickness 0.15)
				)
				(justify left bottom)
			)
		)
		(pad "1" smd roundrect
			(at -0.48 0 90)
			(size 0.59 0.64)
			(layers "F.Cu" "F.Paste" "F.Mask")
			(roundrect_rratio 0.25)
			(net 51 "GND")
			(pintype "passive")
		)
		(pad "2" smd roundrect
			(at 0.48 0 90)
			(size 0.59 0.64)
			(layers "F.Cu" "F.Paste" "F.Mask")
			(roundrect_rratio 0.25)
			(net 133 "+5V_OCU")
			(pintype "passive")
		)
	)
	(footprint "antmicro-footprints:C_0402_1005Metric"
		(layer "F.Cu")
		(at 124.2 141.1)
		(descr "Capacitor SMD 0402")
		(tags "capacitor SMD 0402")
		(property "Reference" "C1"
			(at 2.37325 -0.501466 0)
			(layer "F.SilkS")
			(effects
				(font
					(size 0.7 0.7)
					(thickness 0.15)
				)
				(justify right top)
			)
		)
		(property "Value" "C_10u_0402"
			(at -1.022927 2.155213 0)
			(layer "F.Fab")
			(effects
				(font
					(size 0.7 0.7)
					(thickness 0.15)
				)
				(justify left bottom)
			)
		)
		(property "Footprint" "antmicro-footprints:C_0402_1005Metric"
			(at 0 0 0)
			(layer "F.Fab")
			(hide yes)
			(effects
				(font
					(size 1.27 1.27)
					(thickness 0.15)
				)
			)
		)
		(property "Datasheet" "https://www.yageo.com/en/Chart/Download/pdf/CC0402MRX5R5BB106"
			(at 0 0 0)
			(layer "F.Fab")
			(hide yes)
			(effects
				(font
					(size 1.27 1.27)
					(thickness 0.15)
				)
			)
		)
		(property "Description" "SMD Multilayer Ceramic Capacitor, 10 µF, 6.3 V, 0402 [1005 Metric], ± 20%, X5R, CC Series"
			(at 0 0 0)
			(layer "F.Fab")
			(hide yes)
			(effects
				(font
					(size 1.27 1.27)
					(thickness 0.15)
				)
			)
		)
		(property "MPN" "CC0402MRX5R5BB106"
			(at 0 0 0)
			(unlocked yes)
			(layer "F.Fab")
			(hide yes)
			(effects
				(font
					(size 1 1)
					(thickness 0.15)
				)
			)
		)
		(property "Manufacturer" "YAGEO"
			(at 0 0 0)
			(unlocked yes)
			(layer "F.Fab")
			(hide yes)
			(effects
				(font
					(size 1 1)
					(thickness 0.15)
				)
			)
		)
		(property "License" "Apache-2.0"
			(at 0 0 0)
			(unlocked yes)
			(layer "F.Fab")
			(hide yes)
			(effects
				(font
					(size 1 1)
					(thickness 0.15)
				)
			)
		)
		(property "Author" "Antmicro"
			(at 0 0 0)
			(unlocked yes)
			(layer "F.Fab")
			(hide yes)
			(effects
				(font
					(size 1 1)
					(thickness 0.15)
				)
			)
		)
		(property "Val" "10u"
			(at 0 0 0)
			(unlocked yes)
			(layer "F.Fab")
			(hide yes)
			(effects
				(font
					(size 1 1)
					(thickness 0.15)
				)
			)
		)
		(property "Voltage" ""
			(at 0 0 0)
			(unlocked yes)
			(layer "F.Fab")
			(hide yes)
			(effects
				(font
					(size 1 1)
					(thickness 0.15)
				)
			)
		)
		(property "Dielectric" ""
			(at 0 0 0)
			(unlocked yes)
			(layer "F.Fab")
			(hide yes)
			(effects
				(font
					(size 1 1)
					(thickness 0.15)
				)
			)
		)
		(sheetname "Root")
		(sheetfile "jetson-orin-baseboard-oculink-expansion.kicad_sch")
		(attr smd)
		(fp_rect
			(start -0.925 -0.47)
			(end 0.925 0.47)
			(stroke
				(width 0.05)
				(type default)
			)
			(fill none)
			(layer "F.CrtYd")
		)
		(fp_line
			(start -0.494 -0.25)
			(end 0.504 -0.25)
			(stroke
				(width 0.15)
				(type solid)
			)
			(layer "F.Fab")
		)
		(fp_line
			(start -0.494 0.248)
			(end -0.494 -0.25)
			(stroke
				(width 0.15)
				(type solid)
			)
			(layer "F.Fab")
		)
		(fp_line
			(start 0.504 -0.25)
			(end 0.504 0.248)
			(stroke
				(width 0.15)
				(type solid)
			)
			(layer "F.Fab")
		)
		(fp_line
			(start 0.504 0.248)
			(end -0.494 0.248)
			(stroke
				(width 0.15)
				(type solid)
			)
			(layer "F.Fab")
		)
		(fp_text user "License: Apache-2.0"
			(at -0.939 5.799 0)
			(layer "F.Fab")
			(hide yes)
			(effects
				(font
					(size 0.7 0.7)
					(thickness 0.15)
				)
				(justify left bottom)
			)
		)
		(fp_text user "Author: Antmicro"
			(at -0.939 3.399 0)
			(layer "F.Fab")
			(hide yes)
			(effects
				(font
					(size 0.7 0.7)
					(thickness 0.15)
				)
				(justify left bottom)
			)
		)
		(fp_text user "${REFERENCE}"
			(at -0.939 4.599 0)
			(layer "F.Fab")
			(hide yes)
			(effects
				(font
					(size 0.7 0.7)
					(thickness 0.15)
				)
				(justify left bottom)
			)
		)
		(pad "1" smd roundrect
			(at -0.48 0)
			(size 0.59 0.64)
			(layers "F.Cu" "F.Paste" "F.Mask")
			(roundrect_rratio 0.25)
			(net 51 "GND")
			(pintype "passive")
		)
		(pad "2" smd roundrect
			(at 0.48 0)
			(size 0.59 0.64)
			(layers "F.Cu" "F.Paste" "F.Mask")
			(roundrect_rratio 0.25)
			(net 132 "+3V3_OCU")
			(pintype "passive")
		)
	)
)
